(kicad_pcb
	(version 20260206)
	(generator "pcbnew")
	(generator_version "10.0")
	(general
		(thickness 1.6)
		(legacy_teardrops no)
	)
	(paper "A4")
	(title_block
		(title "01162023_DA0F0TEBIF0_F0T_Expander_BD_F_brd_V02_OCP.brd")
		(comment 1 "Grand Teton / footprints 4575-4580 of 9728")
	)
	(layers
		(0 "F.Cu" signal "TOP")
		(4 "In1.Cu" signal "GND")
		(6 "In2.Cu" signal "VCC")
		(8 "In3.Cu" signal "VCC1")
		(10 "In4.Cu" signal "GND1")
		(12 "In5.Cu" signal "IN1")
		(14 "In6.Cu" signal "GND2")
		(16 "In7.Cu" signal "IN2")
		(18 "In8.Cu" signal "GND3")
		(20 "In9.Cu" signal "IN3")
		(22 "In10.Cu" signal "GND4")
		(24 "In11.Cu" signal "IN4")
		(26 "In12.Cu" signal "GND5")
		(28 "In13.Cu" signal "IN5")
		(30 "In14.Cu" signal "GND6")
		(32 "In15.Cu" signal "IN6")
		(34 "In16.Cu" signal "GND7")
		(2 "B.Cu" signal "BOTTOM")
		(9 "F.Adhes" user "F.Adhesive")
		(11 "B.Adhes" user "B.Adhesive")
		(13 "F.Paste" user "Package Geometry/Pastemask Top")
		(15 "B.Paste" user "Package Geometry/Pastemask Bottom")
		(5 "F.SilkS" user "Ref Des/Silkscreen Top")
		(7 "B.SilkS" user "Ref Des/Silkscreen Bottom")
		(1 "F.Mask" user "Board Geometry/Soldermask Top")
		(3 "B.Mask" user "Board Geometry/Soldermask Bottom")
		(17 "Dwgs.User" user "User.Drawings")
		(19 "Cmts.User" user "User.Comments")
		(21 "Eco1.User" user "User.Eco1")
		(23 "Eco2.User" user "User.Eco2")
		(25 "Edge.Cuts" user "Board Geometry/Outline")
		(27 "Margin" user)
		(31 "F.CrtYd" user "Package Geometry/Place Bound Top")
		(29 "B.CrtYd" user "Package Geometry/Place Bound Bottom")
		(35 "F.Fab" user "Ref Des/Assembly Top")
		(33 "B.Fab" user "Ref Des/Assembly Bottom")
	)
	(footprint ""
		(layer "F.Cu")
		(at 428.83963 -158.219648)
		(property "Reference" "R365"
			(at 0 0 0)
			(layer "F.SilkS")
			(hide yes)
			(effects
				(font
					(size 1.27 1.27)
				)
			)
		)
		(property "Value" ""
			(at 0 0 0)
			(layer "F.Fab")
			(effects
				(font
					(size 1.27 1.27)
				)
			)
		)
		(duplicate_pad_numbers_are_jumpers no)
		(fp_line
			(start -0.7874 -0.4064)
			(end 0.7874 -0.4064)
			(stroke
				(width 0.1524)
				(type default)
			)
			(layer "F.SilkS")
		)
		(fp_line
			(start -0.7874 0.4064)
			(end -0.7874 -0.4064)
			(stroke
				(width 0.1524)
				(type default)
			)
			(layer "F.SilkS")
		)
		(fp_line
			(start 0.7874 -0.4064)
			(end 0.7874 0.4064)
			(stroke
				(width 0.1524)
				(type default)
			)
			(layer "F.SilkS")
		)
		(fp_line
			(start 0.7874 0.4064)
			(end -0.7874 0.4064)
			(stroke
				(width 0.1524)
				(type default)
			)
			(layer "F.SilkS")
		)
		(fp_line
			(start -0.67945 -0.305054)
			(end -0.12065 -0.305054)
			(stroke
				(width 0.1)
				(type default)
			)
			(layer "F.Fab")
		)
		(fp_line
			(start -0.67945 0.3048)
			(end -0.67945 -0.305054)
			(stroke
				(width 0.1)
				(type default)
			)
			(layer "F.Fab")
		)
		(fp_line
			(start -0.12065 -0.305054)
			(end -0.12065 -0.2794)
			(stroke
				(width 0.1)
				(type default)
			)
			(layer "F.Fab")
		)
		(fp_line
			(start -0.12065 -0.2794)
			(end 0.12065 -0.2794)
			(stroke
				(width 0.1)
				(type default)
			)
			(layer "F.Fab")
		)
		(fp_line
			(start -0.12065 0.2794)
			(end -0.12065 0.3048)
			(stroke
				(width 0.1)
				(type default)
			)
			(layer "F.Fab")
		)
		(fp_line
			(start -0.12065 0.3048)
			(end -0.67945 0.3048)
			(stroke
				(width 0.1)
				(type default)
			)
			(layer "F.Fab")
		)
		(fp_line
			(start 0.120396 0.2794)
			(end -0.12065 0.2794)
			(stroke
				(width 0.1)
				(type default)
			)
			(layer "F.Fab")
		)
		(fp_line
			(start 0.120396 0.3048)
			(end 0.120396 0.2794)
			(stroke
				(width 0.1)
				(type default)
			)
			(layer "F.Fab")
		)
		(fp_line
			(start 0.12065 -0.3048)
			(end 0.67945 -0.3048)
			(stroke
				(width 0.1)
				(type default)
			)
			(layer "F.Fab")
		)
		(fp_line
			(start 0.12065 -0.2794)
			(end 0.12065 -0.3048)
			(stroke
				(width 0.1)
				(type default)
			)
			(layer "F.Fab")
		)
		(fp_line
			(start 0.67945 -0.3048)
			(end 0.67945 0.3048)
			(stroke
				(width 0.1)
				(type default)
			)
			(layer "F.Fab")
		)
		(fp_line
			(start 0.67945 0.3048)
			(end 0.120396 0.3048)
			(stroke
				(width 0.1)
				(type default)
			)
			(layer "F.Fab")
		)
		(pad "1" smd circle
			(at -0.40005 0)
			(size 0 0)
			(layers "F.Cu" "F.Mask" "F.Paste")
			(net "PRSNTB3_NIC7_N")
		)
		(pad "2" smd circle
			(at 0.40005 0)
			(size 0 0)
			(layers "F.Cu" "F.Mask" "F.Paste")
			(net "P3V3_AUX")
		)
	)
	(footprint ""
		(layer "F.Cu")
		(at 2.992374 -388.845298 90)
		(property "Reference" "R6748"
			(at 0 0 90)
			(layer "F.SilkS")
			(hide yes)
			(effects
				(font
					(size 1.27 1.27)
				)
			)
		)
		(property "Value" ""
			(at 0 0 90)
			(layer "F.Fab")
			(effects
				(font
					(size 1.27 1.27)
				)
			)
		)
		(duplicate_pad_numbers_are_jumpers no)
		(fp_line
			(start 0.7874 -0.4064)
			(end 0.7874 0.4064)
			(stroke
				(width 0.1524)
				(type default)
			)
			(layer "F.SilkS")
		)
		(fp_line
			(start -0.508762 -0.4064)
			(end 0.7874 -0.4064)
			(stroke
				(width 0.1524)
				(type default)
			)
			(layer "F.SilkS")
		)
		(fp_line
			(start 0.7874 0.4064)
			(end -0.503428 0.4064)
			(stroke
				(width 0.1524)
				(type default)
			)
			(layer "F.SilkS")
		)
		(fp_line
			(start -0.12065 -0.305054)
			(end -0.12065 -0.2794)
			(stroke
				(width 0.1)
				(type default)
			)
			(layer "F.Fab")
		)
		(fp_line
			(start -0.67945 -0.305054)
			(end -0.12065 -0.305054)
			(stroke
				(width 0.1)
				(type default)
			)
			(layer "F.Fab")
		)
		(fp_line
			(start 0.67945 -0.3048)
			(end 0.67945 0.3048)
			(stroke
				(width 0.1)
				(type default)
			)
			(layer "F.Fab")
		)
		(fp_line
			(start 0.12065 -0.3048)
			(end 0.67945 -0.3048)
			(stroke
				(width 0.1)
				(type default)
			)
			(layer "F.Fab")
		)
		(fp_line
			(start 0.12065 -0.2794)
			(end 0.12065 -0.3048)
			(stroke
				(width 0.1)
				(type default)
			)
			(layer "F.Fab")
		)
		(fp_line
			(start -0.12065 -0.2794)
			(end 0.12065 -0.2794)
			(stroke
				(width 0.1)
				(type default)
			)
			(layer "F.Fab")
		)
		(fp_line
			(start 0.120396 0.2794)
			(end -0.12065 0.2794)
			(stroke
				(width 0.1)
				(type default)
			)
			(layer "F.Fab")
		)
		(fp_line
			(start -0.12065 0.2794)
			(end -0.12065 0.3048)
			(stroke
				(width 0.1)
				(type default)
			)
			(layer "F.Fab")
		)
		(fp_line
			(start 0.67945 0.3048)
			(end 0.120396 0.3048)
			(stroke
				(width 0.1)
				(type default)
			)
			(layer "F.Fab")
		)
		(fp_line
			(start 0.120396 0.3048)
			(end 0.120396 0.2794)
			(stroke
				(width 0.1)
				(type default)
			)
			(layer "F.Fab")
		)
		(fp_line
			(start -0.12065 0.3048)
			(end -0.67945 0.3048)
			(stroke
				(width 0.1)
				(type default)
			)
			(layer "F.Fab")
		)
		(fp_line
			(start -0.67945 0.3048)
			(end -0.67945 -0.305054)
			(stroke
				(width 0.1)
				(type default)
			)
			(layer "F.Fab")
		)
		(pad "1" smd circle
			(at -0.40005 0 90)
			(size 0 0)
			(layers "F.Cu" "F.Mask" "F.Paste")
			(net "USB2_MB_BMC_USB8042_DP")
		)
		(pad "2" smd circle
			(at 0.40005 0 90)
			(size 0 0)
			(layers "F.Cu" "F.Mask" "F.Paste")
			(net "GND")
		)
	)
	(footprint ""
		(layer "F.Cu")
		(at 220.34373 -45.88891)
		(property "Reference" "R586"
			(at 0 0 0)
			(layer "F.SilkS")
			(hide yes)
			(effects
				(font
					(size 1.27 1.27)
				)
			)
		)
		(property "Value" ""
			(at 0 0 0)
			(layer "F.Fab")
			(effects
				(font
					(size 1.27 1.27)
				)
			)
		)
		(duplicate_pad_numbers_are_jumpers no)
		(fp_line
			(start -0.7874 -0.4064)
			(end 0.7874 -0.4064)
			(stroke
				(width 0.1524)
				(type default)
			)
			(layer "F.SilkS")
		)
		(fp_line
			(start -0.7874 0.4064)
			(end -0.7874 -0.4064)
			(stroke
				(width 0.1524)
				(type default)
			)
			(layer "F.SilkS")
		)
		(fp_line
			(start 0.7874 -0.4064)
			(end 0.7874 0.4064)
			(stroke
				(width 0.1524)
				(type default)
			)
			(layer "F.SilkS")
		)
		(fp_line
			(start 0.7874 0.4064)
			(end -0.7874 0.4064)
			(stroke
				(width 0.1524)
				(type default)
			)
			(layer "F.SilkS")
		)
		(fp_line
			(start -0.67945 -0.305054)
			(end -0.12065 -0.305054)
			(stroke
				(width 0.1)
				(type default)
			)
			(layer "F.Fab")
		)
		(fp_line
			(start -0.67945 0.3048)
			(end -0.67945 -0.305054)
			(stroke
				(width 0.1)
				(type default)
			)
			(layer "F.Fab")
		)
		(fp_line
			(start -0.12065 -0.305054)
			(end -0.12065 -0.2794)
			(stroke
				(width 0.1)
				(type default)
			)
			(layer "F.Fab")
		)
		(fp_line
			(start -0.12065 -0.2794)
			(end 0.12065 -0.2794)
			(stroke
				(width 0.1)
				(type default)
			)
			(layer "F.Fab")
		)
		(fp_line
			(start -0.12065 0.2794)
			(end -0.12065 0.3048)
			(stroke
				(width 0.1)
				(type default)
			)
			(layer "F.Fab")
		)
		(fp_line
			(start -0.12065 0.3048)
			(end -0.67945 0.3048)
			(stroke
				(width 0.1)
				(type default)
			)
			(layer "F.Fab")
		)
		(fp_line
			(start 0.120396 0.2794)
			(end -0.12065 0.2794)
			(stroke
				(width 0.1)
				(type default)
			)
			(layer "F.Fab")
		)
		(fp_line
			(start 0.120396 0.3048)
			(end 0.120396 0.2794)
			(stroke
				(width 0.1)
				(type default)
			)
			(layer "F.Fab")
		)
		(fp_line
			(start 0.12065 -0.3048)
			(end 0.67945 -0.3048)
			(stroke
				(width 0.1)
				(type default)
			)
			(layer "F.Fab")
		)
		(fp_line
			(start 0.12065 -0.2794)
			(end 0.12065 -0.3048)
			(stroke
				(width 0.1)
				(type default)
			)
			(layer "F.Fab")
		)
		(fp_line
			(start 0.67945 -0.3048)
			(end 0.67945 0.3048)
			(stroke
				(width 0.1)
				(type default)
			)
			(layer "F.Fab")
		)
		(fp_line
			(start 0.67945 0.3048)
			(end 0.120396 0.3048)
			(stroke
				(width 0.1)
				(type default)
			)
			(layer "F.Fab")
		)
		(pad "1" smd circle
			(at -0.40005 0)
			(size 0 0)
			(layers "F.Cu" "F.Mask" "F.Paste")
			(net "SSD7_ADC_A0")
		)
		(pad "2" smd circle
			(at 0.40005 0)
			(size 0 0)
			(layers "F.Cu" "F.Mask" "F.Paste")
			(net "GND")
		)
	)
	(footprint ""
		(layer "F.Cu")
		(at 263.50976 -344.772488)
		(property "Reference" "R6652"
			(at 0 0 0)
			(layer "F.SilkS")
			(hide yes)
			(effects
				(font
					(size 1.27 1.27)
				)
			)
		)
		(property "Value" ""
			(at 0 0 0)
			(layer "F.Fab")
			(effects
				(font
					(size 1.27 1.27)
				)
			)
		)
		(duplicate_pad_numbers_are_jumpers no)
		(fp_line
			(start -0.7874 -0.4064)
			(end 0.7874 -0.4064)
			(stroke
				(width 0.1524)
				(type default)
			)
			(layer "F.SilkS")
		)
		(fp_line
			(start -0.7874 0.4064)
			(end -0.7874 -0.4064)
			(stroke
				(width 0.1524)
				(type default)
			)
			(layer "F.SilkS")
		)
		(fp_line
			(start 0.7874 -0.4064)
			(end 0.7874 0.4064)
			(stroke
				(width 0.1524)
				(type default)
			)
			(layer "F.SilkS")
		)
		(fp_line
			(start 0.7874 0.4064)
			(end -0.7874 0.4064)
			(stroke
				(width 0.1524)
				(type default)
			)
			(layer "F.SilkS")
		)
		(fp_line
			(start -0.67945 -0.305054)
			(end -0.12065 -0.305054)
			(stroke
				(width 0.1)
				(type default)
			)
			(layer "F.Fab")
		)
		(fp_line
			(start -0.67945 0.3048)
			(end -0.67945 -0.305054)
			(stroke
				(width 0.1)
				(type default)
			)
			(layer "F.Fab")
		)
		(fp_line
			(start -0.12065 -0.305054)
			(end -0.12065 -0.2794)
			(stroke
				(width 0.1)
				(type default)
			)
			(layer "F.Fab")
		)
		(fp_line
			(start -0.12065 -0.2794)
			(end 0.12065 -0.2794)
			(stroke
				(width 0.1)
				(type default)
			)
			(layer "F.Fab")
		)
		(fp_line
			(start -0.12065 0.2794)
			(end -0.12065 0.3048)
			(stroke
				(width 0.1)
				(type default)
			)
			(layer "F.Fab")
		)
		(fp_line
			(start -0.12065 0.3048)
			(end -0.67945 0.3048)
			(stroke
				(width 0.1)
				(type default)
			)
			(layer "F.Fab")
		)
		(fp_line
			(start 0.120396 0.2794)
			(end -0.12065 0.2794)
			(stroke
				(width 0.1)
				(type default)
			)
			(layer "F.Fab")
		)
		(fp_line
			(start 0.120396 0.3048)
			(end 0.120396 0.2794)
			(stroke
				(width 0.1)
				(type default)
			)
			(layer "F.Fab")
		)
		(fp_line
			(start 0.12065 -0.3048)
			(end 0.67945 -0.3048)
			(stroke
				(width 0.1)
				(type default)
			)
			(layer "F.Fab")
		)
		(fp_line
			(start 0.12065 -0.2794)
			(end 0.12065 -0.3048)
			(stroke
				(width 0.1)
				(type default)
			)
			(layer "F.Fab")
		)
		(fp_line
			(start 0.67945 -0.3048)
			(end 0.67945 0.3048)
			(stroke
				(width 0.1)
				(type default)
			)
			(layer "F.Fab")
		)
		(fp_line
			(start 0.67945 0.3048)
			(end 0.120396 0.3048)
			(stroke
				(width 0.1)
				(type default)
			)
			(layer "F.Fab")
		)
		(pad "1" smd circle
			(at -0.40005 0)
			(size 0 0)
			(layers "F.Cu" "F.Mask" "F.Paste")
			(net "P3V3_AUX")
		)
		(pad "2" smd circle
			(at 0.40005 0)
			(size 0 0)
			(layers "F.Cu" "F.Mask" "F.Paste")
			(net "HSC_D_OC_R")
		)
	)
	(footprint ""
		(layer "F.Cu")
		(at 8.362696 -171.64431 180)
		(property "Reference" "PC21"
			(at 0 0 180)
			(layer "F.SilkS")
			(hide yes)
			(effects
				(font
					(size 1.27 1.27)
				)
			)
		)
		(property "Value" ""
			(at 0 0 180)
			(layer "F.Fab")
			(effects
				(font
					(size 1.27 1.27)
				)
			)
		)
		(duplicate_pad_numbers_are_jumpers no)
		(fp_line
			(start 1.524 0.762)
			(end -1.524 0.762)
			(stroke
				(width 0.1524)
				(type default)
			)
			(layer "F.SilkS")
		)
		(fp_line
			(start 1.524 -0.762)
			(end 1.524 0.762)
			(stroke
				(width 0.1524)
				(type default)
			)
			(layer "F.SilkS")
		)
		(fp_line
			(start -1.524 0.762)
			(end -1.524 -0.762)
			(stroke
				(width 0.1524)
				(type default)
			)
			(layer "F.SilkS")
		)
		(fp_line
			(start -1.524 -0.762)
			(end 1.524 -0.762)
			(stroke
				(width 0.1524)
				(type default)
			)
			(layer "F.SilkS")
		)
		(fp_line
			(start 1.1049 0.724916)
			(end 1.1049 -0.724916)
			(stroke
				(width 0.1)
				(type default)
			)
			(layer "F.Fab")
		)
		(fp_line
			(start 1.1049 -0.724916)
			(end -1.1049 -0.724916)
			(stroke
				(width 0.1)
				(type default)
			)
			(layer "F.Fab")
		)
		(fp_line
			(start -1.1049 0.724916)
			(end 1.1049 0.724916)
			(stroke
				(width 0.1)
				(type default)
			)
			(layer "F.Fab")
		)
		(fp_line
			(start -1.1049 -0.724916)
			(end -1.1049 0.724916)
			(stroke
				(width 0.1)
				(type default)
			)
			(layer "F.Fab")
		)
		(pad "1" smd rect
			(at -0.889 0)
			(size 1.016 1.27)
			(layers "F.Cu" "F.Mask" "F.Paste")
			(net "P5V_AUX")
		)
		(pad "2" smd rect
			(at 0.889 0)
			(size 1.016 1.27)
			(layers "F.Cu" "F.Mask" "F.Paste")
			(net "GND")
		)
	)
	(footprint ""
		(layer "F.Cu")
		(at 338.074 -147.955 180)
		(property "Reference" "R4831"
			(at 0 0 180)
			(layer "F.SilkS")
			(hide yes)
			(effects
				(font
					(size 1.27 1.27)
				)
			)
		)
		(property "Value" ""
			(at 0 0 180)
			(layer "F.Fab")
			(effects
				(font
					(size 1.27 1.27)
				)
			)
		)
		(duplicate_pad_numbers_are_jumpers no)
		(fp_line
			(start 0.7874 0.4064)
			(end -0.7874 0.4064)
			(stroke
				(width 0.1524)
				(type default)
			)
			(layer "F.SilkS")
		)
		(fp_line
			(start 0.7874 -0.4064)
			(end 0.7874 0.4064)
			(stroke
				(width 0.1524)
				(type default)
			)
			(layer "F.SilkS")
		)
		(fp_line
			(start -0.7874 0.4064)
			(end -0.7874 -0.4064)
			(stroke
				(width 0.1524)
				(type default)
			)
			(layer "F.SilkS")
		)
		(fp_line
			(start -0.7874 -0.4064)
			(end 0.7874 -0.4064)
			(stroke
				(width 0.1524)
				(type default)
			)
			(layer "F.SilkS")
		)
		(fp_line
			(start 0.67945 0.3048)
			(end 0.120396 0.3048)
			(stroke
				(width 0.1)
				(type default)
			)
			(layer "F.Fab")
		)
		(fp_line
			(start 0.67945 -0.3048)
			(end 0.67945 0.3048)
			(stroke
				(width 0.1)
				(type default)
			)
			(layer "F.Fab")
		)
		(fp_line
			(start 0.12065 -0.2794)
			(end 0.12065 -0.3048)
			(stroke
				(width 0.1)
				(type default)
			)
			(layer "F.Fab")
		)
		(fp_line
			(start 0.12065 -0.3048)
			(end 0.67945 -0.3048)
			(stroke
				(width 0.1)
				(type default)
			)
			(layer "F.Fab")
		)
		(fp_line
			(start 0.120396 0.3048)
			(end 0.120396 0.2794)
			(stroke
				(width 0.1)
				(type default)
			)
			(layer "F.Fab")
		)
		(fp_line
			(start 0.120396 0.2794)
			(end -0.12065 0.2794)
			(stroke
				(width 0.1)
				(type default)
			)
			(layer "F.Fab")
		)
		(fp_line
			(start -0.12065 0.3048)
			(end -0.67945 0.3048)
			(stroke
				(width 0.1)
				(type default)
			)
			(layer "F.Fab")
		)
		(fp_line
			(start -0.12065 0.2794)
			(end -0.12065 0.3048)
			(stroke
				(width 0.1)
				(type default)
			)
			(layer "F.Fab")
		)
		(fp_line
			(start -0.12065 -0.2794)
			(end 0.12065 -0.2794)
			(stroke
				(width 0.1)
				(type default)
			)
			(layer "F.Fab")
		)
		(fp_line
			(start -0.12065 -0.305054)
			(end -0.12065 -0.2794)
			(stroke
				(width 0.1)
				(type default)
			)
			(layer "F.Fab")
		)
		(fp_line
			(start -0.67945 0.3048)
			(end -0.67945 -0.305054)
			(stroke
				(width 0.1)
				(type default)
			)
			(layer "F.Fab")
		)
		(fp_line
			(start -0.67945 -0.305054)
			(end -0.12065 -0.305054)
			(stroke
				(width 0.1)
				(type default)
			)
			(layer "F.Fab")
		)
		(pad "1" smd circle
			(at -0.40005 0 180)
			(size 0 0)
			(layers "F.Cu" "F.Mask" "F.Paste")
			(net "PRSNT_SSD14_FPGA_PCA9555_N")
		)
		(pad "2" smd circle
			(at 0.40005 0 180)
			(size 0 0)
			(layers "F.Cu" "F.Mask" "F.Paste")
			(net "PRSNT_SSD14_FPGA_R_N")
		)
	)
)
